# SCM (Grand Teton) — schematic netlist excerpt (pin names and nets, part order shuffled) for the footprints in the layout excerpt that follows; sources: Cadence DE-HDL packaged netlist, KiCad conversion of 12092022_DA0F0TMDCD0_F0T_Management_Board_D_brd_V3_OCP.brd

R382  Q_RES  0 5% CHIP  pkg 0402LF  page 53 : A = PWRGD_P3V3_AUX ; B = PWRGD_P3V3_AUX_R2
PR276  Q_RES  5.49K 1% CHIP  pkg 0402LF  page 52 : A = GND ; B = P3V3_AUX_CS

(kicad_pcb
	(version 20260206)
	(generator "pcbnew")
	(generator_version "10.0")
	(general
		(thickness 1.6)
		(legacy_teardrops no)
	)
	(paper "A4")
	(title_block
		(title "12092022_DA0F0TMDCD0_F0T_Management_Board_D_brd_V3_OCP.brd")
		(comment 1 "Grand Teton / footprints 151-152 of 1440")
	)
	(layers
		(0 "F.Cu" signal "TOP")
		(4 "In1.Cu" signal "GND")
		(6 "In2.Cu" signal "IN1")
		(8 "In3.Cu" signal "GND1")
		(10 "In4.Cu" signal "IN2")
		(12 "In5.Cu" signal "VCC")
		(14 "In6.Cu" signal "VCC1")
		(16 "In7.Cu" signal "IN3")
		(18 "In8.Cu" signal "GND2")
		(20 "In9.Cu" signal "IN4")
		(22 "In10.Cu" signal "GND3")
		(2 "B.Cu" signal "BOTTOM")
		(9 "F.Adhes" user "F.Adhesive")
		(11 "B.Adhes" user "B.Adhesive")
		(13 "F.Paste" user "Package Geometry/Pastemask Top")
		(15 "B.Paste" user "Package Geometry/Pastemask Bottom")
		(5 "F.SilkS" user "Ref Des/Silkscreen Top")
		(7 "B.SilkS" user "Ref Des/Silkscreen Bottom")
		(1 "F.Mask" user "Board Geometry/Soldermask Top")
		(3 "B.Mask" user "Board Geometry/Soldermask Bottom")
		(17 "Dwgs.User" user "User.Drawings")
		(19 "Cmts.User" user "User.Comments")
		(21 "Eco1.User" user "User.Eco1")
		(23 "Eco2.User" user "User.Eco2")
		(25 "Edge.Cuts" user "Board Geometry/Outline")
		(27 "Margin" user)
		(31 "F.CrtYd" user "Package Geometry/Place Bound Top")
		(29 "B.CrtYd" user "Package Geometry/Place Bound Bottom")
		(35 "F.Fab" user "Ref Des/Assembly Top")
		(33 "B.Fab" user "Ref Des/Assembly Bottom")
	)
	(footprint ""
		(layer "F.Cu")
		(at 9.649968 -62.513464 180)
		(property "Reference" "PR276"
			(at 0 0 180)
			(layer "F.SilkS")
			(hide yes)
			(effects
				(font
					(size 1.27 1.27)
				)
			)
		)
		(property "Value" ""
			(at 0 0 180)
			(layer "F.Fab")
			(effects
				(font
					(size 1.27 1.27)
				)
			)
		)
		(duplicate_pad_numbers_are_jumpers no)
		(fp_line
			(start 0.7874 0.4064)
			(end -0.7874 0.4064)
			(stroke
				(width 0.1524)
				(type default)
			)
			(layer "F.SilkS")
		)
		(fp_line
			(start 0.7874 -0.4064)
			(end 0.7874 0.4064)
			(stroke
				(width 0.1524)
				(type default)
			)
			(layer "F.SilkS")
		)
		(fp_line
			(start -0.7874 0.4064)
			(end -0.7874 -0.4064)
			(stroke
				(width 0.1524)
				(type default)
			)
			(layer "F.SilkS")
		)
		(fp_line
			(start -0.7874 -0.4064)
			(end 0.7874 -0.4064)
			(stroke
				(width 0.1524)
				(type default)
			)
			(layer "F.SilkS")
		)
		(fp_line
			(start 0.67945 0.3048)
			(end 0.120396 0.3048)
			(stroke
				(width 0.1)
				(type default)
			)
			(layer "F.Fab")
		)
		(fp_line
			(start 0.67945 -0.3048)
			(end 0.67945 0.3048)
			(stroke
				(width 0.1)
				(type default)
			)
			(layer "F.Fab")
		)
		(fp_line
			(start 0.12065 -0.2794)
			(end 0.12065 -0.3048)
			(stroke
				(width 0.1)
				(type default)
			)
			(layer "F.Fab")
		)
		(fp_line
			(start 0.12065 -0.3048)
			(end 0.67945 -0.3048)
			(stroke
				(width 0.1)
				(type default)
			)
			(layer "F.Fab")
		)
		(fp_line
			(start 0.120396 0.3048)
			(end 0.120396 0.2794)
			(stroke
				(width 0.1)
				(type default)
			)
			(layer "F.Fab")
		)
		(fp_line
			(start 0.120396 0.2794)
			(end -0.12065 0.2794)
			(stroke
				(width 0.1)
				(type default)
			)
			(layer "F.Fab")
		)
		(fp_line
			(start -0.12065 0.3048)
			(end -0.67945 0.3048)
			(stroke
				(width 0.1)
				(type default)
			)
			(layer "F.Fab")
		)
		(fp_line
			(start -0.12065 0.2794)
			(end -0.12065 0.3048)
			(stroke
				(width 0.1)
				(type default)
			)
			(layer "F.Fab")
		)
		(fp_line
			(start -0.12065 -0.2794)
			(end 0.12065 -0.2794)
			(stroke
				(width 0.1)
				(type default)
			)
			(layer "F.Fab")
		)
		(fp_line
			(start -0.12065 -0.305054)
			(end -0.12065 -0.2794)
			(stroke
				(width 0.1)
				(type default)
			)
			(layer "F.Fab")
		)
		(fp_line
			(start -0.67945 0.3048)
			(end -0.67945 -0.305054)
			(stroke
				(width 0.1)
				(type default)
			)
			(layer "F.Fab")
		)
		(fp_line
			(start -0.67945 -0.305054)
			(end -0.12065 -0.305054)
			(stroke
				(width 0.1)
				(type default)
			)
			(layer "F.Fab")
		)
		(pad "1" smd circle
			(at -0.40005 0 180)
			(size 0 0)
			(layers "F.Cu" "F.Mask" "F.Paste")
			(net "GND")
		)
		(pad "2" smd circle
			(at 0.40005 0 180)
			(size 0 0)
			(layers "F.Cu" "F.Mask" "F.Paste")
			(net "P3V3_AUX_CS")
		)
	)
	(footprint ""
		(layer "F.Cu")
		(at 81.501488 -30.150308 90)
		(property "Reference" "R382"
			(at 0 0 90)
			(layer "F.SilkS")
			(hide yes)
			(effects
				(font
					(size 1.27 1.27)
				)
			)
		)
		(property "Value" ""
			(at 0 0 90)
			(layer "F.Fab")
			(effects
				(font
					(size 1.27 1.27)
				)
			)
		)
		(duplicate_pad_numbers_are_jumpers no)
		(fp_line
			(start 0.7874 -0.4064)
			(end 0.7874 0.4064)
			(stroke
				(width 0.1524)
				(type default)
			)
			(layer "F.SilkS")
		)
		(fp_line
			(start -0.7874 -0.4064)
			(end 0.7874 -0.4064)
			(stroke
				(width 0.1524)
				(type default)
			)
			(layer "F.SilkS")
		)
		(fp_line
			(start 0.7874 0.4064)
			(end -0.7874 0.4064)
			(stroke
				(width 0.1524)
				(type default)
			)
			(layer "F.SilkS")
		)
		(fp_line
			(start -0.7874 0.4064)
			(end -0.7874 -0.4064)
			(stroke
				(width 0.1524)
				(type default)
			)
			(layer "F.SilkS")
		)
		(fp_line
			(start -0.12065 -0.305054)
			(end -0.12065 -0.2794)
			(stroke
				(width 0.1)
				(type default)
			)
			(layer "F.Fab")
		)
		(fp_line
			(start -0.67945 -0.305054)
			(end -0.12065 -0.305054)
			(stroke
				(width 0.1)
				(type default)
			)
			(layer "F.Fab")
		)
		(fp_line
			(start 0.67945 -0.3048)
			(end 0.67945 0.3048)
			(stroke
				(width 0.1)
				(type default)
			)
			(layer "F.Fab")
		)
		(fp_line
			(start 0.12065 -0.3048)
			(end 0.67945 -0.3048)
			(stroke
				(width 0.1)
				(type default)
			)
			(layer "F.Fab")
		)
		(fp_line
			(start 0.12065 -0.2794)
			(end 0.12065 -0.3048)
			(stroke
				(width 0.1)
				(type default)
			)
			(layer "F.Fab")
		)
		(fp_line
			(start -0.12065 -0.2794)
			(end 0.12065 -0.2794)
			(stroke
				(width 0.1)
				(type default)
			)
			(layer "F.Fab")
		)
		(fp_line
			(start 0.120396 0.2794)
			(end -0.12065 0.2794)
			(stroke
				(width 0.1)
				(type default)
			)
			(layer "F.Fab")
		)
		(fp_line
			(start -0.12065 0.2794)
			(end -0.12065 0.3048)
			(stroke
				(width 0.1)
				(type default)
			)
			(layer "F.Fab")
		)
		(fp_line
			(start 0.67945 0.3048)
			(end 0.120396 0.3048)
			(stroke
				(width 0.1)
				(type default)
			)
			(layer "F.Fab")
		)
		(fp_line
			(start 0.120396 0.3048)
			(end 0.120396 0.2794)
			(stroke
				(width 0.1)
				(type default)
			)
			(layer "F.Fab")
		)
		(fp_line
			(start -0.12065 0.3048)
			(end -0.67945 0.3048)
			(stroke
				(width 0.1)
				(type default)
			)
			(layer "F.Fab")
		)
		(fp_line
			(start -0.67945 0.3048)
			(end -0.67945 -0.305054)
			(stroke
				(width 0.1)
				(type default)
			)
			(layer "F.Fab")
		)
		(pad "1" smd circle
			(at -0.40005 0 90)
			(size 0 0)
			(layers "F.Cu" "F.Mask" "F.Paste")
			(net "PWRGD_P3V3_AUX")
		)
		(pad "2" smd circle
			(at 0.40005 0 90)
			(size 0 0)
			(layers "F.Cu" "F.Mask" "F.Paste")
			(net "PWRGD_P3V3_AUX_R2")
		)
	)
)
